(kicad_pcb
	(version 20260206)
	(generator "pcbnew")
	(generator_version "10.0")
	(general
		(thickness 1.6)
		(legacy_teardrops no)
	)
	(paper "A4")
	(title_block
		(title "pdpb — Lightning_PDPB_BRD.brd")
		(comment 1 "Lightning (Wiwynn / Facebook NVMe JBOF) / footprints 172-178 of 1140")
	)
	(layers
		(0 "F.Cu" signal "TOP")
		(4 "In1.Cu" signal "L2GND")
		(6 "In2.Cu" signal "L3")
		(8 "In3.Cu" signal "L4VCC")
		(10 "In4.Cu" signal "L5VCC")
		(12 "In5.Cu" signal "L6")
		(14 "In6.Cu" signal "L7GND")
		(2 "B.Cu" signal "BOTTOM")
		(9 "F.Adhes" user "F.Adhesive")
		(11 "B.Adhes" user "B.Adhesive")
		(13 "F.Paste" user "Package Geometry/Pastemask Top")
		(15 "B.Paste" user "Package Geometry/Pastemask Bottom")
		(5 "F.SilkS" user "Ref Des/Silkscreen Top")
		(7 "B.SilkS" user "Ref Des/Silkscreen Bottom")
		(1 "F.Mask" user "Board Geometry/Soldermask Top")
		(3 "B.Mask" user "Board Geometry/Soldermask Bottom")
		(17 "Dwgs.User" user "User.Drawings")
		(19 "Cmts.User" user "User.Comments")
		(21 "Eco1.User" user "User.Eco1")
		(23 "Eco2.User" user "User.Eco2")
		(25 "Edge.Cuts" user "Board Geometry/Outline")
		(27 "Margin" user)
		(31 "F.CrtYd" user "Package Geometry/Place Bound Top")
		(29 "B.CrtYd" user "Package Geometry/Place Bound Bottom")
		(35 "F.Fab" user "Ref Des/Assembly Top")
		(33 "B.Fab" user "Ref Des/Assembly Bottom")
	)
	(footprint ""
		(layer "F.Cu")
		(at 227.203 -439.166 180)
		(property "Reference" "PC1275"
			(at 0 0 180)
			(layer "F.SilkS")
			(hide yes)
			(effects
				(font
					(size 1.27 1.27)
				)
			)
		)
		(property "Value" "SC2D2U16V2KX-GP"
			(at -1.524 -1.905 180)
			(unlocked yes)
			(layer "F.Fab")
			(hide yes)
			(effects
				(font
					(size 1.016 1.016)
					(thickness 0.1524)
				)
			)
		)
		(property "Device Type" "C402-TO0D2H28"
			(at -1.524 -3.429 180)
			(unlocked yes)
			(layer "F.Fab")
			(hide yes)
			(effects
				(font
					(size 1.016 1.016)
					(thickness 0.1524)
				)
			)
		)
		(duplicate_pad_numbers_are_jumpers no)
		(fp_rect
			(start -0.4826 0.889)
			(end 0.4826 -0.889)
			(stroke
				(width 0)
				(type default)
			)
			(fill no)
			(layer "F.CrtYd")
		)
		(fp_rect
			(start -0.4826 0.889)
			(end 0.4826 -0.889)
			(stroke
				(width 0)
				(type default)
			)
			(fill no)
			(layer "F.Fab")
		)
		(pad "1" smd custom
			(at 0 -0.4572 180)
			(size 0.1524 0.1524)
			(layers "F.Cu" "F.Mask" "F.Paste")
			(net "P3V3_EN_R")
			(options
				(clearance outline)
				(anchor circle)
			)
			(primitives
				(gr_poly
					(pts
						(arc
							(start -0.254 0.3048)
							(mid -0.325842 0.275042)
							(end -0.3556 0.2032)
						)
						(arc
							(start -0.3556 -0.2032)
							(mid -0.325842 -0.275042)
							(end -0.254 -0.3048)
						)
						(arc
							(start 0.254 -0.3048)
							(mid 0.325842 -0.275042)
							(end 0.3556 -0.2032)
						)
						(arc
							(start 0.3556 0.2032)
							(mid 0.325842 0.275042)
							(end 0.254 0.3048)
						)
					)
					(width 0)
					(fill yes)
				)
			)
		)
		(pad "2" smd custom
			(at 0 0.4572 180)
			(size 0.1524 0.1524)
			(layers "F.Cu" "F.Mask" "F.Paste")
			(net "AGND_P3V3")
			(options
				(clearance outline)
				(anchor circle)
			)
			(primitives
				(gr_poly
					(pts
						(arc
							(start -0.254 0.3048)
							(mid -0.325842 0.275042)
							(end -0.3556 0.2032)
						)
						(arc
							(start -0.3556 -0.2032)
							(mid -0.325842 -0.275042)
							(end -0.254 -0.3048)
						)
						(arc
							(start 0.254 -0.3048)
							(mid 0.325842 -0.275042)
							(end 0.3556 -0.2032)
						)
						(arc
							(start 0.3556 0.2032)
							(mid 0.325842 0.275042)
							(end 0.254 0.3048)
						)
					)
					(width 0)
					(fill yes)
				)
			)
		)
	)
	(footprint ""
		(layer "F.Cu")
		(at 223.012 -438.404 180)
		(property "Reference" "PC1287"
			(at 0 0 180)
			(layer "F.SilkS")
			(hide yes)
			(effects
				(font
					(size 1.27 1.27)
				)
			)
		)
		(property "Value" "SC2K2P50V3KX-GP"
			(at 0 -2.8194 180)
			(unlocked yes)
			(layer "F.Fab")
			(hide yes)
			(effects
				(font
					(size 1.016 1.016)
					(thickness 0.1524)
				)
			)
		)
		(property "Device Type" "C603"
			(at 0 -4.3434 180)
			(unlocked yes)
			(layer "F.Fab")
			(hide yes)
			(effects
				(font
					(size 1.016 1.016)
					(thickness 0.1524)
				)
			)
		)
		(duplicate_pad_numbers_are_jumpers no)
		(fp_line
			(start 0.508 0)
			(end -0.508 0)
			(stroke
				(width 0.2032)
				(type default)
			)
			(layer "F.SilkS")
		)
		(fp_rect
			(start -0.5842 1.3335)
			(end 0.5842 -1.3335)
			(stroke
				(width 0)
				(type default)
			)
			(fill no)
			(layer "F.CrtYd")
		)
		(fp_rect
			(start -0.5842 1.3335)
			(end 0.5842 -1.3335)
			(stroke
				(width 0)
				(type default)
			)
			(fill no)
			(layer "F.Fab")
		)
		(pad "1" smd custom
			(at 0 -0.762 180)
			(size 0.2159 0.2159)
			(layers "F.Cu" "F.Mask" "F.Paste")
			(net "P3V3_SW")
			(options
				(clearance outline)
				(anchor circle)
			)
			(primitives
				(gr_poly
					(pts
						(arc
							(start -0.3302 -0.4318)
							(mid -0.402042 -0.402042)
							(end -0.4318 -0.3302)
						)
						(arc
							(start -0.4318 0.3302)
							(mid -0.402042 0.402042)
							(end -0.3302 0.4318)
						)
						(arc
							(start 0.3302 0.4318)
							(mid 0.402042 0.402042)
							(end 0.4318 0.3302)
						)
						(arc
							(start 0.4318 -0.3302)
							(mid 0.402042 -0.402042)
							(end 0.3302 -0.4318)
						)
					)
					(width 0)
					(fill yes)
				)
			)
		)
		(pad "2" smd custom
			(at 0 0.762 180)
			(size 0.2159 0.2159)
			(layers "F.Cu" "F.Mask" "F.Paste")
			(net "P3V3_SNB")
			(options
				(clearance outline)
				(anchor circle)
			)
			(primitives
				(gr_poly
					(pts
						(arc
							(start -0.3302 -0.4318)
							(mid -0.402042 -0.402042)
							(end -0.4318 -0.3302)
						)
						(arc
							(start -0.4318 0.3302)
							(mid -0.402042 0.402042)
							(end -0.3302 0.4318)
						)
						(arc
							(start 0.3302 0.4318)
							(mid 0.402042 0.402042)
							(end 0.4318 0.3302)
						)
						(arc
							(start 0.4318 -0.3302)
							(mid 0.402042 -0.402042)
							(end 0.3302 -0.4318)
						)
					)
					(width 0)
					(fill yes)
				)
			)
		)
	)
	(footprint ""
		(layer "F.Cu")
		(at 210.49996 -459.000098 -90)
		(property "Reference" "U47"
			(at 0 0 270)
			(layer "F.SilkS")
			(hide yes)
			(effects
				(font
					(size 1.27 1.27)
				)
			)
		)
		(property "Value" "TMP75AIDGKR-GP"
			(at -0.1143 -9.1948 270)
			(unlocked yes)
			(layer "F.Fab")
			(hide yes)
			(effects
				(font
					(size 1.016 1.016)
					(thickness 0.1524)
				)
			)
		)
		(property "Device Type" "MSOP8-1H44"
			(at -0.1143 -10.795 270)
			(unlocked yes)
			(layer "F.Fab")
			(hide yes)
			(effects
				(font
					(size 1.016 1.016)
					(thickness 0.1524)
				)
			)
		)
		(duplicate_pad_numbers_are_jumpers no)
		(fp_line
			(start -1.778 1.0922)
			(end -1.778 3.048)
			(stroke
				(width 0.508)
				(type default)
			)
			(layer "F.SilkS")
		)
		(fp_line
			(start -1.9558 1.016)
			(end 1.0795 1.016)
			(stroke
				(width 0.1524)
				(type default)
			)
			(layer "F.SilkS")
		)
		(fp_line
			(start 1.0795 1.016)
			(end 1.0795 -1.016)
			(stroke
				(width 0.1524)
				(type default)
			)
			(layer "F.SilkS")
		)
		(fp_line
			(start -1.4478 -0.0381)
			(end -1.9558 0.4699)
			(stroke
				(width 0.1524)
				(type default)
			)
			(layer "F.SilkS")
		)
		(fp_line
			(start -1.9558 -0.5461)
			(end -1.4478 -0.0381)
			(stroke
				(width 0.1524)
				(type default)
			)
			(layer "F.SilkS")
		)
		(fp_line
			(start -1.9558 -1.016)
			(end -1.9558 1.016)
			(stroke
				(width 0.1524)
				(type default)
			)
			(layer "F.SilkS")
		)
		(fp_line
			(start 1.0795 -1.016)
			(end -1.9558 -1.016)
			(stroke
				(width 0.1524)
				(type default)
			)
			(layer "F.SilkS")
		)
		(fp_poly
			(pts
				(xy -1.1557 -1.016) (xy -1.1557 1.016) (xy 1.1557 1.016) (xy 1.1557 -1.016)
			)
			(stroke
				(width 0)
				(type default)
			)
			(fill yes)
			(layer "F.SilkS")
		)
		(fp_rect
			(start -1.4986 2.4511)
			(end 1.4986 -2.4511)
			(stroke
				(width 0)
				(type default)
			)
			(fill no)
			(layer "F.CrtYd")
		)
		(fp_poly
			(pts
				(xy -2.032 3.302) (xy -2.032 -3.302) (xy 2.032 -3.302) (xy 2.032 -2.1209) (xy 1.4986 -2.1209) (xy 1.4986 -2.4511)
				(xy -1.4986 -2.4511) (xy -1.4986 2.4511) (xy 1.4986 2.4511) (xy 1.4986 -2.1082) (xy 2.032 -2.1082)
				(xy 2.032 3.302)
			)
			(stroke
				(width 0)
				(type default)
			)
			(fill no)
			(layer "F.CrtYd")
		)
		(fp_rect
			(start -2.032 3.302)
			(end 2.032 -3.302)
			(stroke
				(width 0)
				(type default)
			)
			(fill no)
			(layer "F.Fab")
		)
		(pad "1" smd rect
			(at -0.97536 2.05486 270)
			(size 0.3556 1.524)
			(layers "F.Cu" "F.Mask" "F.Paste")
			(net "TMP2_SDA")
		)
		(pad "2" smd rect
			(at -0.32512 2.05486 270)
			(size 0.3556 1.524)
			(layers "F.Cu" "F.Mask" "F.Paste")
			(net "TMP2_SCL")
		)
		(pad "3" smd rect
			(at 0.32512 2.05486 270)
			(size 0.3556 1.524)
			(layers "F.Cu" "F.Mask" "F.Paste")
			(net "I2C_B_TMP2_ALERT")
		)
		(pad "4" smd rect
			(at 0.97536 2.05486 270)
			(size 0.3556 1.524)
			(layers "F.Cu" "F.Mask" "F.Paste")
			(net "GND")
		)
		(pad "5" smd rect
			(at 0.97536 -2.05486 270)
			(size 0.3556 1.524)
			(layers "F.Cu" "F.Mask" "F.Paste")
			(net "I2C_B_TMP2_A2")
		)
		(pad "6" smd rect
			(at 0.32512 -2.05486 270)
			(size 0.3556 1.524)
			(layers "F.Cu" "F.Mask" "F.Paste")
			(net "I2C_B_TMP2_A1")
		)
		(pad "7" smd rect
			(at -0.32512 -2.05486 270)
			(size 0.3556 1.524)
			(layers "F.Cu" "F.Mask" "F.Paste")
			(net "I2C_B_TMP2_A0")
		)
		(pad "8" smd rect
			(at -0.97536 -2.05486 270)
			(size 0.3556 1.524)
			(layers "F.Cu" "F.Mask" "F.Paste")
			(net "P3V3")
		)
	)
	(footprint ""
		(layer "F.Cu")
		(at 19.4945 -59.073288 180)
		(property "Reference" "R9875"
			(at 0 0 180)
			(layer "F.SilkS")
			(hide yes)
			(effects
				(font
					(size 1.27 1.27)
				)
			)
		)
		(property "Value" "0R2J-2-GP"
			(at 0.064008 -3.993896 180)
			(unlocked yes)
			(layer "F.Fab")
			(hide yes)
			(effects
				(font
					(size 1.016 1.016)
					(thickness 0.1524)
				)
			)
		)
		(property "Device Type" "R402H16"
			(at 0.064008 -5.517896 180)
			(unlocked yes)
			(layer "F.Fab")
			(hide yes)
			(effects
				(font
					(size 1.016 1.016)
					(thickness 0.1524)
				)
			)
		)
		(duplicate_pad_numbers_are_jumpers no)
		(fp_line
			(start 0.508 -0.9398)
			(end -0.508 -0.9398)
			(stroke
				(width 0.1524)
				(type default)
			)
			(layer "F.SilkS")
		)
		(fp_line
			(start -0.508 -0.9398)
			(end -0.508 0.9398)
			(stroke
				(width 0.1524)
				(type default)
			)
			(layer "F.SilkS")
		)
		(fp_rect
			(start -0.508 0.9398)
			(end 0.508 -0.9398)
			(stroke
				(width 0)
				(type default)
			)
			(fill no)
			(layer "F.CrtYd")
		)
		(fp_rect
			(start -0.508 0.9398)
			(end 0.508 -0.9398)
			(stroke
				(width 0)
				(type default)
			)
			(fill no)
			(layer "F.Fab")
		)
		(pad "1" smd custom
			(at 0 -0.4445 180)
			(size 0.1397 0.1397)
			(layers "F.Cu" "F.Mask" "F.Paste")
			(net "SSD_ACT_DR14_R")
			(options
				(clearance outline)
				(anchor circle)
			)
			(primitives
				(gr_poly
					(pts
						(arc
							(start -0.1778 -0.2794)
							(mid -0.249642 -0.249642)
							(end -0.2794 -0.1778)
						)
						(arc
							(start -0.2794 0.1778)
							(mid -0.249642 0.249642)
							(end -0.1778 0.2794)
						)
						(arc
							(start 0.1778 0.2794)
							(mid 0.249642 0.249642)
							(end 0.2794 0.1778)
						)
						(arc
							(start 0.2794 -0.1778)
							(mid 0.249642 -0.249642)
							(end 0.1778 -0.2794)
						)
					)
					(width 0)
					(fill yes)
				)
			)
		)
		(pad "2" smd custom
			(at 0 0.4445 180)
			(size 0.1397 0.1397)
			(layers "F.Cu" "F.Mask" "F.Paste")
			(net "SSD_ACT_DR14")
			(options
				(clearance outline)
				(anchor circle)
			)
			(primitives
				(gr_poly
					(pts
						(arc
							(start -0.1778 -0.2794)
							(mid -0.249642 -0.249642)
							(end -0.2794 -0.1778)
						)
						(arc
							(start -0.2794 0.1778)
							(mid -0.249642 0.249642)
							(end -0.1778 0.2794)
						)
						(arc
							(start 0.1778 0.2794)
							(mid 0.249642 0.249642)
							(end 0.2794 0.1778)
						)
						(arc
							(start 0.2794 -0.1778)
							(mid 0.249642 -0.249642)
							(end 0.1778 -0.2794)
						)
					)
					(width 0)
					(fill yes)
				)
			)
		)
	)
	(footprint ""
		(layer "F.Cu")
		(at 25.1206 -420.1922 180)
		(property "Reference" "PC1183"
			(at 0 0 180)
			(layer "F.SilkS")
			(hide yes)
			(effects
				(font
					(size 1.27 1.27)
				)
			)
		)
		(property "Value" "SCD01U50V2KX-1GP"
			(at 1.1811 -2.7051 180)
			(unlocked yes)
			(layer "F.Fab")
			(hide yes)
			(effects
				(font
					(size 1.016 1.016)
					(thickness 0.1524)
				)
			)
		)
		(property "Device Type" "C402H22"
			(at 1.1811 -4.2291 180)
			(unlocked yes)
			(layer "F.Fab")
			(hide yes)
			(effects
				(font
					(size 1.016 1.016)
					(thickness 0.1524)
				)
			)
		)
		(duplicate_pad_numbers_are_jumpers no)
		(fp_rect
			(start -0.4318 0.9525)
			(end 0.4318 -0.9525)
			(stroke
				(width 0)
				(type default)
			)
			(fill no)
			(layer "F.CrtYd")
		)
		(fp_rect
			(start -0.4318 0.9525)
			(end 0.4318 -0.9525)
			(stroke
				(width 0)
				(type default)
			)
			(fill no)
			(layer "F.Fab")
		)
		(pad "1" smd custom
			(at 0 -0.4445 180)
			(size 0.1524 0.1524)
			(layers "F.Cu" "F.Mask" "F.Paste")
			(net "P12V_SSD10")
			(options
				(clearance outline)
				(anchor circle)
			)
			(primitives
				(gr_poly
					(pts
						(arc
							(start 0.3048 -0.2032)
							(mid 0.275042 -0.275042)
							(end 0.2032 -0.3048)
						)
						(arc
							(start -0.2032 -0.3048)
							(mid -0.275042 -0.275042)
							(end -0.3048 -0.2032)
						)
						(arc
							(start -0.3048 0.2032)
							(mid -0.275042 0.275042)
							(end -0.2032 0.3048)
						)
						(arc
							(start 0.2032 0.3048)
							(mid 0.275042 0.275042)
							(end 0.3048 0.2032)
						)
					)
					(width 0)
					(fill yes)
				)
			)
		)
		(pad "2" smd custom
			(at 0 0.4445 180)
			(size 0.1524 0.1524)
			(layers "F.Cu" "F.Mask" "F.Paste")
			(net "GND")
			(options
				(clearance outline)
				(anchor circle)
			)
			(primitives
				(gr_poly
					(pts
						(arc
							(start 0.3048 -0.2032)
							(mid 0.275042 -0.275042)
							(end 0.2032 -0.3048)
						)
						(arc
							(start -0.2032 -0.3048)
							(mid -0.275042 -0.275042)
							(end -0.3048 -0.2032)
						)
						(arc
							(start -0.3048 0.2032)
							(mid -0.275042 0.275042)
							(end -0.2032 0.3048)
						)
						(arc
							(start 0.2032 0.3048)
							(mid 0.275042 0.275042)
							(end 0.3048 0.2032)
						)
					)
					(width 0)
					(fill yes)
				)
			)
		)
	)
	(footprint ""
		(layer "F.Cu")
		(at 41.672764 -347.936058 180)
		(property "Reference" "R9940"
			(at 0 0 180)
			(layer "F.SilkS")
			(hide yes)
			(effects
				(font
					(size 1.27 1.27)
				)
			)
		)
		(property "Value" "4K7R2J-2-GP"
			(at 0.064008 -3.993896 180)
			(unlocked yes)
			(layer "F.Fab")
			(hide yes)
			(effects
				(font
					(size 1.016 1.016)
					(thickness 0.1524)
				)
			)
		)
		(property "Device Type" "R402H16"
			(at 0.064008 -5.517896 180)
			(unlocked yes)
			(layer "F.Fab")
			(hide yes)
			(effects
				(font
					(size 1.016 1.016)
					(thickness 0.1524)
				)
			)
		)
		(duplicate_pad_numbers_are_jumpers no)
		(fp_line
			(start 0.508 -0.9398)
			(end -0.508 -0.9398)
			(stroke
				(width 0.1524)
				(type default)
			)
			(layer "F.SilkS")
		)
		(fp_line
			(start -0.508 -0.9398)
			(end -0.508 0.9398)
			(stroke
				(width 0.1524)
				(type default)
			)
			(layer "F.SilkS")
		)
		(fp_rect
			(start -0.508 0.9398)
			(end 0.508 -0.9398)
			(stroke
				(width 0)
				(type default)
			)
			(fill no)
			(layer "F.CrtYd")
		)
		(fp_rect
			(start -0.508 0.9398)
			(end 0.508 -0.9398)
			(stroke
				(width 0)
				(type default)
			)
			(fill no)
			(layer "F.Fab")
		)
		(pad "1" smd custom
			(at 0 -0.4445 180)
			(size 0.1397 0.1397)
			(layers "F.Cu" "F.Mask" "F.Paste")
			(net "P3V3")
			(options
				(clearance outline)
				(anchor circle)
			)
			(primitives
				(gr_poly
					(pts
						(arc
							(start -0.1778 -0.2794)
							(mid -0.249642 -0.249642)
							(end -0.2794 -0.1778)
						)
						(arc
							(start -0.2794 0.1778)
							(mid -0.249642 0.249642)
							(end -0.1778 0.2794)
						)
						(arc
							(start 0.1778 0.2794)
							(mid 0.249642 0.249642)
							(end 0.2794 0.1778)
						)
						(arc
							(start 0.2794 -0.1778)
							(mid 0.249642 -0.249642)
							(end 0.1778 -0.2794)
						)
					)
					(width 0)
					(fill yes)
				)
			)
		)
		(pad "2" smd custom
			(at 0 0.4445 180)
			(size 0.1397 0.1397)
			(layers "F.Cu" "F.Mask" "F.Paste")
			(net "SSD_ACT_DR6_MOS_N")
			(options
				(clearance outline)
				(anchor circle)
			)
			(primitives
				(gr_poly
					(pts
						(arc
							(start -0.1778 -0.2794)
							(mid -0.249642 -0.249642)
							(end -0.2794 -0.1778)
						)
						(arc
							(start -0.2794 0.1778)
							(mid -0.249642 0.249642)
							(end -0.1778 0.2794)
						)
						(arc
							(start 0.1778 0.2794)
							(mid 0.249642 0.249642)
							(end 0.2794 0.1778)
						)
						(arc
							(start 0.2794 -0.1778)
							(mid 0.249642 -0.249642)
							(end 0.1778 -0.2794)
						)
					)
					(width 0)
					(fill yes)
				)
			)
		)
	)
	(footprint ""
		(layer "F.Cu")
		(at 78.8162 -430.3395 180)
		(property "Reference" "R9957"
			(at 0 0 180)
			(layer "F.SilkS")
			(hide yes)
			(effects
				(font
					(size 1.27 1.27)
				)
			)
		)
		(property "Value" "470R2F-GP"
			(at 0.064008 -3.993896 180)
			(unlocked yes)
			(layer "F.Fab")
			(hide yes)
			(effects
				(font
					(size 1.016 1.016)
					(thickness 0.1524)
				)
			)
		)
		(property "Device Type" "R402H16"
			(at 0.064008 -5.517896 180)
			(unlocked yes)
			(layer "F.Fab")
			(hide yes)
			(effects
				(font
					(size 1.016 1.016)
					(thickness 0.1524)
				)
			)
		)
		(duplicate_pad_numbers_are_jumpers no)
		(fp_line
			(start 0.508 -0.9398)
			(end -0.508 -0.9398)
			(stroke
				(width 0.1524)
				(type default)
			)
			(layer "F.SilkS")
		)
		(fp_line
			(start -0.508 -0.9398)
			(end -0.508 0.9398)
			(stroke
				(width 0.1524)
				(type default)
			)
			(layer "F.SilkS")
		)
		(fp_rect
			(start -0.508 0.9398)
			(end 0.508 -0.9398)
			(stroke
				(width 0)
				(type default)
			)
			(fill no)
			(layer "F.CrtYd")
		)
		(fp_rect
			(start -0.508 0.9398)
			(end 0.508 -0.9398)
			(stroke
				(width 0)
				(type default)
			)
			(fill no)
			(layer "F.Fab")
		)
		(pad "1" smd custom
			(at 0 -0.4445 180)
			(size 0.1397 0.1397)
			(layers "F.Cu" "F.Mask" "F.Paste")
			(net "VDD_DIFF_1")
			(options
				(clearance outline)
				(anchor circle)
			)
			(primitives
				(gr_poly
					(pts
						(arc
							(start -0.1778 -0.2794)
							(mid -0.249642 -0.249642)
							(end -0.2794 -0.1778)
						)
						(arc
							(start -0.2794 0.1778)
							(mid -0.249642 0.249642)
							(end -0.1778 0.2794)
						)
						(arc
							(start 0.1778 0.2794)
							(mid 0.249642 0.249642)
							(end 0.2794 0.1778)
						)
						(arc
							(start 0.2794 -0.1778)
							(mid 0.249642 -0.249642)
							(end 0.1778 -0.2794)
						)
					)
					(width 0)
					(fill yes)
				)
			)
		)
		(pad "2" smd custom
			(at 0 0.4445 180)
			(size 0.1397 0.1397)
			(layers "F.Cu" "F.Mask" "F.Paste")
			(net "PE_100M_CLK4_N")
			(options
				(clearance outline)
				(anchor circle)
			)
			(primitives
				(gr_poly
					(pts
						(arc
							(start -0.1778 -0.2794)
							(mid -0.249642 -0.249642)
							(end -0.2794 -0.1778)
						)
						(arc
							(start -0.2794 0.1778)
							(mid -0.249642 0.249642)
							(end -0.1778 0.2794)
						)
						(arc
							(start 0.1778 0.2794)
							(mid 0.249642 0.249642)
							(end 0.2794 0.1778)
						)
						(arc
							(start 0.2794 -0.1778)
							(mid 0.249642 -0.249642)
							(end 0.1778 -0.2794)
						)
					)
					(width 0)
					(fill yes)
				)
			)
		)
	)
)
